# BASEBOARD_FAB2 (Tioga Pass) — schematic netlist excerpt (pin names and nets, part order shuffled) for the footprints in the layout excerpt that follows; sources: Cadence DE-HDL packaged netlist, KiCad conversion of Wiwynn_Tioga_Pass_MB.brd

J1B2  CONN6_C74770005  0.22UF 16V 10% HDR  pkg PIP  page 251
  IO1  = GND
  IO2  = P12V_PUMP
  IO3  = PUMP_TACH_D
  IO4  = PUMP_PWM_OUT_R
  IO5  = PUMP_TACH1_D
  IO6  = TP_PUMP

(kicad_pcb
	(version 20260206)
	(generator "pcbnew")
	(generator_version "10.0")
	(general
		(thickness 1.6)
		(legacy_teardrops no)
	)
	(paper "A4")
	(title_block
		(title "Wiwynn_Tioga_Pass_MB.brd")
		(comment 1 "Tioga Pass / footprints 1606-1606 of 4770")
	)
	(layers
		(0 "F.Cu" signal "TOP")
		(4 "In1.Cu" signal "L2GND")
		(6 "In2.Cu" signal "L3")
		(8 "In3.Cu" signal "L4GND")
		(10 "In4.Cu" signal "L5")
		(12 "In5.Cu" signal "L6GND")
		(14 "In6.Cu" signal "L7VCC")
		(16 "In7.Cu" signal "L8VCC")
		(18 "In8.Cu" signal "L9GND")
		(20 "In9.Cu" signal "L10")
		(22 "In10.Cu" signal "L11GND")
		(24 "In11.Cu" signal "L12")
		(26 "In12.Cu" signal "L13GND")
		(2 "B.Cu" signal "BOTTOM")
		(9 "F.Adhes" user "F.Adhesive")
		(11 "B.Adhes" user "B.Adhesive")
		(13 "F.Paste" user "Package Geometry/Pastemask Top")
		(15 "B.Paste" user "Package Geometry/Pastemask Bottom")
		(5 "F.SilkS" user "Ref Des/Silkscreen Top")
		(7 "B.SilkS" user "Ref Des/Silkscreen Bottom")
		(1 "F.Mask" user "Board Geometry/Soldermask Top")
		(3 "B.Mask" user "Board Geometry/Soldermask Bottom")
		(17 "Dwgs.User" user "User.Drawings")
		(19 "Cmts.User" user "User.Comments")
		(21 "Eco1.User" user "User.Eco1")
		(23 "Eco2.User" user "User.Eco2")
		(25 "Edge.Cuts" user "Board Geometry/Outline")
		(27 "Margin" user)
		(31 "F.CrtYd" user "Package Geometry/Place Bound Top")
		(29 "B.CrtYd" user "Package Geometry/Place Bound Bottom")
		(35 "F.Fab" user "Ref Des/Assembly Top")
		(33 "B.Fab" user "Ref Des/Assembly Bottom")
	)
	(footprint ""
		(layer "F.Cu")
		(at 15.370048 -118.679976 -90)
		(property "Reference" "J1B2"
			(at -1.9558 15.89913 90)
			(unlocked yes)
			(layer "F.SilkS")
			(effects
				(font
					(size 0.7874 0.5842)
					(thickness 0.1524)
				)
			)
		)
		(property "Value" ""
			(at 0 0 270)
			(layer "F.Fab")
			(effects
				(font
					(size 1.27 1.27)
				)
			)
		)
		(duplicate_pad_numbers_are_jumpers no)
		(fp_line
			(start -3.47472 14.14526)
			(end 2.71526 14.14526)
			(stroke
				(width 0.1524)
				(type default)
			)
			(layer "F.SilkS")
		)
		(fp_line
			(start 2.71526 14.14526)
			(end 2.71526 6.1722)
			(stroke
				(width 0.1524)
				(type default)
			)
			(layer "F.SilkS")
		)
		(fp_line
			(start 2.71526 3.9878)
			(end 2.71526 -1.44526)
			(stroke
				(width 0.1524)
				(type default)
			)
			(layer "F.SilkS")
		)
		(fp_line
			(start -3.47472 -1.44526)
			(end -3.47472 14.14526)
			(stroke
				(width 0.1524)
				(type default)
			)
			(layer "F.SilkS")
		)
		(fp_line
			(start 2.71526 -1.44526)
			(end -3.47472 -1.44526)
			(stroke
				(width 0.1524)
				(type default)
			)
			(layer "F.SilkS")
		)
		(fp_poly
			(pts
				(xy -5.2578 0.4445) (xy -5.2578 -0.5715) (xy -3.9878 -0.0635)
			)
			(stroke
				(width 0)
				(type default)
			)
			(fill yes)
			(layer "F.SilkS")
		)
		(fp_poly
			(pts
				(xy -2.4511 -0.13716) (xy -2.4511 -1.15316) (xy -1.1811 -0.64516)
			)
			(stroke
				(width 0)
				(type default)
			)
			(fill yes)
			(layer "B.SilkS")
		)
		(fp_poly
			(pts
				(xy 2.71526 -1.44526) (xy 2.71526 14.14526) (xy -3.47472 14.14526) (xy -3.47472 -1.44526)
			)
			(stroke
				(width 0)
				(type default)
			)
			(fill no)
			(layer "F.CrtYd")
		)
		(fp_poly
			(pts
				(xy -5.27558 0.4445) (xy -5.27558 -0.5715) (xy -4.00558 -0.0635)
			)
			(stroke
				(width 0)
				(type default)
			)
			(fill yes)
			(layer "B.Fab")
		)
		(fp_line
			(start -3.47472 14.14526)
			(end -3.47472 -1.44526)
			(stroke
				(width 0.1)
				(type default)
			)
			(layer "F.Fab")
		)
		(fp_line
			(start 2.71526 14.14526)
			(end -3.47472 14.14526)
			(stroke
				(width 0.1)
				(type default)
			)
			(layer "F.Fab")
		)
		(fp_line
			(start -3.47472 -1.44526)
			(end 2.71526 -1.44526)
			(stroke
				(width 0.1)
				(type default)
			)
			(layer "F.Fab")
		)
		(fp_line
			(start 2.71526 -1.44526)
			(end 2.71526 14.14526)
			(stroke
				(width 0.1)
				(type default)
			)
			(layer "F.Fab")
		)
		(fp_poly
			(pts
				(xy -5.2578 0.4445) (xy -5.2578 -0.5715) (xy -3.9878 -0.0635)
			)
			(stroke
				(width 0)
				(type default)
			)
			(fill yes)
			(layer "F.Fab")
		)
		(fp_text user "6"
			(at -3.434334 15.171928 0)
			(unlocked yes)
			(layer "F.SilkS")
			(effects
				(font
					(size 0.7874 0.5842)
					(thickness 0.1524)
				)
			)
		)
		(fp_text user "6"
			(at -3.628644 13.098018 270)
			(unlocked yes)
			(layer "B.SilkS")
			(effects
				(font
					(size 0.7874 0.5842)
					(thickness 0.1524)
				)
				(justify mirror)
			)
		)
		(fp_text user "6"
			(at -4.08178 12.91209 270)
			(unlocked yes)
			(layer "B.Fab")
			(effects
				(font
					(size 0.7874 0.5842)
					(thickness 0.1524)
				)
				(justify mirror)
			)
		)
		(fp_text user "6"
			(at -1.462024 -1.9939 270)
			(unlocked yes)
			(layer "F.Fab")
			(effects
				(font
					(size 0.7874 0.5842)
					(thickness 0.1524)
				)
			)
		)
		(pad "" np_thru_hole circle
			(at 2.159 5.08 270)
			(size 0.254 0.254)
			(drill 1.4986)
			(layers "*.Cu" "*.Mask")
			(clearance 0.9398)
			(thermal_gap 0.9398)
		)
		(pad "1" thru_hole rect
			(at 0 0 270)
			(size 1.524 1.524)
			(drill 1.143)
			(layers "*.Cu" "*.Mask")
			(remove_unused_layers no)
			(net "GND")
			(clearance 0.127)
			(thermal_gap 0.127)
			(padstack
				(mode front_inner_back)
				(layer "Inner"
					(shape circle)
					(size 1.524 1.524)
					(clearance 0.127)
				)
				(layer "B.Cu"
					(shape rect)
					(size 1.524 1.524)
					(clearance 0.127)
				)
			)
		)
		(pad "2" thru_hole circle
			(at 0 2.54 270)
			(size 1.524 1.524)
			(drill 1.143)
			(layers "*.Cu" "*.Mask")
			(remove_unused_layers no)
			(net "P12V_PUMP")
			(clearance 0.127)
			(thermal_gap 0.127)
		)
		(pad "3" thru_hole circle
			(at 0 5.08 270)
			(size 1.524 1.524)
			(drill 1.143)
			(layers "*.Cu" "*.Mask")
			(remove_unused_layers no)
			(net "PUMP_TACH_D")
			(clearance 0.127)
			(thermal_gap 0.127)
		)
		(pad "4" thru_hole circle
			(at 0 7.62 270)
			(size 1.524 1.524)
			(drill 1.143)
			(layers "*.Cu" "*.Mask")
			(remove_unused_layers no)
			(net "PUMP_PWM_OUT_R")
			(clearance 0.127)
			(thermal_gap 0.127)
		)
		(pad "5" thru_hole circle
			(at 0 10.16 270)
			(size 1.524 1.524)
			(drill 1.143)
			(layers "*.Cu" "*.Mask")
			(remove_unused_layers no)
			(net "PUMP_TACH1_D")
			(clearance 0.127)
			(thermal_gap 0.127)
		)
		(pad "6" thru_hole circle
			(at 0 12.7 270)
			(size 1.524 1.524)
			(drill 1.143)
			(layers "*.Cu" "*.Mask")
			(remove_unused_layers no)
			(net "TP_PUMP")
			(clearance 0.127)
			(thermal_gap 0.127)
		)
		(zone
			(layers "F.Cu" "B.Cu" "In1.Cu" "In2.Cu" "In3.Cu" "In4.Cu" "In5.Cu" "In6.Cu"
				"In7.Cu" "In8.Cu" "In9.Cu" "In10.Cu" "In11.Cu" "In12.Cu"
			)
			(hatch none 0.5)
			(connect_pads
				(clearance 0)
			)
			(min_thickness 0.25)
			(keepout
				(tracks not_allowed)
				(vias allowed)
				(pads allowed)
				(copperpour not_allowed)
				(footprints allowed)
			)
			(placement
				(enabled no)
				(sheetname "")
			)
			(fill
				(thermal_gap 0.5)
				(thermal_bridge_width 0.5)
				(island_removal_mode 0)
			)
			(polygon
				(pts
					(arc
						(start 11.356848 -116.520976)
						(mid 9.223248 -116.520976)
						(end 11.356848 -116.520976)
					)
				)
			)
		)
	)
)
